#ISCELL
  cls sheet_a1 *
  *
#ISCELL
  cls offpage_out *
  page522_i11
#ISCELL
  cls offpage_out *
  page522_i12
#ISCELL
  cls offpage_out *
  page522_i13
#ISCELL
  cls offpage_out *
  page522_i14
#CELL
  passive capacitor *
  page522_i142
#CELL
  passive capacitor *
  page522_i143
#CELL
  clock osc6p_v2 *
  page522_i144
#CELL
  clock osc6p_v2 *
  page522_i145
#CELL
  passive ferritebead *
  page522_i146
#CELL
  passive capacitor *
  page522_i147
#CELL
  passive resistor *
  page522_i149
#ISCELL
  cls gnd_sg *
  page522_i150
#CELL
  passive capacitor *
  page522_i151
#CELL
  passive capacitor *
  page522_i152
#CELL
  passive capacitor *
  page522_i153
#CELL
  passive capacitor *
  page522_i154
#ISCELL
  cls gnd_sg *
  page522_i155
#CELL
  passive resistor *
  page522_i156
#CELL
  passive capacitor *
  page522_i158
#CELL
  passive ferritebead *
  page522_i159
#CELL
  passive capacitor *
  page522_i160
#CELL
  passive capacitor *
  page522_i161
#ISCELL
  cls gnd_sg *
  page522_i167
#ISCELL
  cls gnd_sg *
  page522_i168
#CELL
  passive resistor *
  page522_i169
#CELL
  passive resistor *
  page522_i170
#ISCELL
  cls gnd_sg *
  page522_i171
#CELL
  passive resistor *
  page522_i172
#ISCELL
  cls gnd_sg *
  page522_i173
#CELL
  passive resistor *
  page522_i174
#ISCELL
  cls vcc *
  page522_i176
#ISCELL
  cls vcc *
  page522_i177
#ISCELL
  cls offpage_in *
  page522_i178
#ISCELL
  cls offpage_in *
  page522_i179
